(kicad_pcb
	(version 20260206)
	(generator "pcbnew")
	(generator_version "10.0")
	(general
		(thickness 1.6)
		(legacy_teardrops no)
	)
	(paper "A4")
	(title_block
		(title "ptb — Lightning_PTB_BRD.brd")
		(comment 1 "Lightning (Wiwynn / Facebook NVMe JBOF) / footprints 30-32 of 61")
	)
	(layers
		(0 "F.Cu" signal "TOP")
		(4 "In1.Cu" signal "L2GND")
		(6 "In2.Cu" signal "L3VCC")
		(2 "B.Cu" signal "BOTTOM")
		(9 "F.Adhes" user "F.Adhesive")
		(11 "B.Adhes" user "B.Adhesive")
		(13 "F.Paste" user "Package Geometry/Pastemask Top")
		(15 "B.Paste" user "Package Geometry/Pastemask Bottom")
		(5 "F.SilkS" user "Ref Des/Silkscreen Top")
		(7 "B.SilkS" user "Ref Des/Silkscreen Bottom")
		(1 "F.Mask" user "Board Geometry/Soldermask Top")
		(3 "B.Mask" user "Board Geometry/Soldermask Bottom")
		(17 "Dwgs.User" user "User.Drawings")
		(19 "Cmts.User" user "User.Comments")
		(21 "Eco1.User" user "User.Eco1")
		(23 "Eco2.User" user "User.Eco2")
		(25 "Edge.Cuts" user "Board Geometry/Outline")
		(27 "Margin" user)
		(31 "F.CrtYd" user "Package Geometry/Place Bound Top")
		(29 "B.CrtYd" user "Package Geometry/Place Bound Bottom")
		(35 "F.Fab" user "Ref Des/Assembly Top")
		(33 "B.Fab" user "Ref Des/Assembly Bottom")
	)
	(footprint ""
		(layer "F.Cu")
		(at 147.660106 -110.000034)
		(property "Reference" "SW1"
			(at 0 0 0)
			(layer "F.SilkS")
			(hide yes)
			(effects
				(font
					(size 1.27 1.27)
				)
			)
		)
		(property "Value" "SW-PUSH-3P-3-GP"
			(at 18.9357 -6.1341 0)
			(unlocked yes)
			(layer "F.Fab")
			(hide yes)
			(effects
				(font
					(size 1.016 1.016)
					(thickness 0.1524)
				)
			)
		)
		(property "Device Type" "MS-B1PL-10"
			(at 18.9357 -7.6581 0)
			(unlocked yes)
			(layer "F.Fab")
			(hide yes)
			(effects
				(font
					(size 1.016 1.016)
					(thickness 0.1524)
				)
			)
		)
		(duplicate_pad_numbers_are_jumpers no)
		(fp_line
			(start -6.6294 0.3302)
			(end -6.096 0.3302)
			(stroke
				(width 0.1524)
				(type default)
			)
			(layer "F.SilkS")
		)
		(fp_line
			(start -6.6294 2.8575)
			(end -6.6294 0.3302)
			(stroke
				(width 0.1524)
				(type default)
			)
			(layer "F.SilkS")
		)
		(fp_line
			(start -6.096 -2.8575)
			(end 4.6228 -2.8575)
			(stroke
				(width 0.1524)
				(type default)
			)
			(layer "F.SilkS")
		)
		(fp_line
			(start -6.096 0.3302)
			(end -6.096 -2.8575)
			(stroke
				(width 0.1524)
				(type default)
			)
			(layer "F.SilkS")
		)
		(fp_line
			(start 4.6228 -3.3528)
			(end 19.9136 -3.3528)
			(stroke
				(width 0.1524)
				(type default)
			)
			(layer "F.SilkS")
		)
		(fp_line
			(start 4.6228 -2.8575)
			(end 4.6228 -3.3528)
			(stroke
				(width 0.1524)
				(type default)
			)
			(layer "F.SilkS")
		)
		(fp_line
			(start 5.8928 2.8575)
			(end -6.6294 2.8575)
			(stroke
				(width 0.1524)
				(type default)
			)
			(layer "F.SilkS")
		)
		(fp_line
			(start 5.8928 3.3528)
			(end 5.8928 2.8575)
			(stroke
				(width 0.1524)
				(type default)
			)
			(layer "F.SilkS")
		)
		(fp_line
			(start 19.9136 -3.3528)
			(end 19.9136 3.3528)
			(stroke
				(width 0.1524)
				(type default)
			)
			(layer "F.SilkS")
		)
		(fp_line
			(start 19.9136 3.3528)
			(end 5.8928 3.3528)
			(stroke
				(width 0.1524)
				(type default)
			)
			(layer "F.SilkS")
		)
		(fp_circle
			(center -5.5499 1.400048)
			(end -4.3815 1.400048)
			(stroke
				(width 0.3048)
				(type default)
			)
			(fill no)
			(layer "F.SilkS")
		)
		(fp_circle
			(center -2.500122 0)
			(end -1.484122 0)
			(stroke
				(width 0.3048)
				(type default)
			)
			(fill no)
			(layer "F.SilkS")
		)
		(fp_circle
			(center 0 0)
			(end 1.016 0)
			(stroke
				(width 0.3048)
				(type default)
			)
			(fill no)
			(layer "F.SilkS")
		)
		(fp_circle
			(center 2.500122 0)
			(end 3.516122 0)
			(stroke
				(width 0.3048)
				(type default)
			)
			(fill no)
			(layer "F.SilkS")
		)
		(fp_circle
			(center 5.700014 -2.29997)
			(end 6.868414 -2.29997)
			(stroke
				(width 0.3048)
				(type default)
			)
			(fill no)
			(layer "F.SilkS")
		)
		(fp_poly
			(pts
				(xy -5.842 -2.6035) (xy 6.1468 -2.6035) (xy 6.1468 -3.0988) (xy 19.6596 -3.0988) (xy 19.6596 3.0988)
				(xy 6.1468 3.0988) (xy 6.1468 2.6035) (xy -5.842 2.6035)
			)
			(stroke
				(width 0)
				(type default)
			)
			(fill no)
			(layer "F.CrtYd")
		)
		(fp_poly
			(pts
				(xy 5.6388 3.6068) (xy 5.6388 3.1115) (xy -6.8834 3.1115) (xy -6.8834 0.0762) (xy -6.35 0.0762)
				(xy -6.35 -3.1115) (xy 4.3688 -3.1115) (xy 4.3688 -3.6068) (xy 20.1676 -3.6068) (xy 20.1676 -0.00635)
				(xy 19.6596 -0.00635) (xy 19.6596 -3.0988) (xy 6.1468 -3.0988) (xy 6.1468 -2.6035) (xy -5.842 -2.6035)
				(xy -5.842 2.6035) (xy 6.1468 2.6035) (xy 6.1468 3.0988) (xy 19.6596 3.0988) (xy 19.6596 0.00635)
				(xy 20.1676 0.00635) (xy 20.1676 3.6068)
			)
			(stroke
				(width 0)
				(type default)
			)
			(fill no)
			(layer "F.CrtYd")
		)
		(fp_poly
			(pts
				(xy 5.6388 3.6068) (xy 5.6388 3.1115) (xy -6.8834 3.1115) (xy -6.8834 0.0762) (xy -6.35 0.0762)
				(xy -6.35 -3.1115) (xy 4.3688 -3.1115) (xy 4.3688 -3.6068) (xy 20.1676 -3.6068) (xy 20.1676 3.6068)
			)
			(stroke
				(width 0)
				(type default)
			)
			(fill no)
			(layer "F.Fab")
		)
		(pad "1" thru_hole circle
			(at 2.500122 0)
			(size 1.3208 1.3208)
			(drill 0.9144)
			(layers "*.Cu" "*.Mask")
			(remove_unused_layers no)
			(net "TPS2490_EN1")
			(clearance 0.1524)
			(thermal_gap 0.1524)
		)
		(pad "2" thru_hole circle
			(at 0 0)
			(size 1.3208 1.3208)
			(drill 0.9144)
			(layers "*.Cu" "*.Mask")
			(remove_unused_layers no)
			(net "TPS2490_EN2")
			(clearance 0.1524)
			(thermal_gap 0.1524)
		)
		(pad "3" thru_hole circle
			(at -2.500122 0)
			(size 1.3208 1.3208)
			(drill 0.9144)
			(layers "*.Cu" "*.Mask")
			(remove_unused_layers no)
			(net "TPS2490_DISABLE")
			(clearance 0.1524)
			(thermal_gap 0.1524)
		)
		(pad "4" thru_hole circle
			(at 5.700014 -2.29997)
			(size 1.6256 1.6256)
			(drill 1.2192)
			(layers "*.Cu" "*.Mask")
			(remove_unused_layers no)
			(net "GND")
			(clearance 0.1524)
			(thermal_gap 0.1524)
		)
		(pad "5" thru_hole circle
			(at -5.5499 1.400048)
			(size 1.6256 1.6256)
			(drill 1.2192)
			(layers "*.Cu" "*.Mask")
			(remove_unused_layers no)
			(net "GND")
			(clearance 0.1524)
			(thermal_gap 0.1524)
		)
		(zone
			(layer "F.Cu")
			(hatch none 0.5)
			(connect_pads
				(clearance 0)
			)
			(min_thickness 0.25)
			(keepout
				(tracks allowed)
				(vias not_allowed)
				(pads allowed)
				(copperpour not_allowed)
				(footprints allowed)
			)
			(placement
				(enabled no)
				(sheetname "")
			)
			(fill
				(thermal_gap 0.5)
				(thermal_bridge_width 0.5)
				(island_removal_mode 0)
			)
			(polygon
				(pts
					(xy 141.683232 -109.412786) (xy 142.53718 -109.412786) (xy 142.53718 -110.076996) (xy 141.683232 -110.076996)
				)
			)
		)
		(zone
			(layer "F.Cu")
			(hatch none 0.5)
			(connect_pads
				(clearance 0)
			)
			(min_thickness 0.25)
			(keepout
				(tracks not_allowed)
				(vias allowed)
				(pads allowed)
				(copperpour not_allowed)
				(footprints allowed)
			)
			(placement
				(enabled no)
				(sheetname "")
			)
			(fill
				(thermal_gap 0.5)
				(thermal_bridge_width 0.5)
				(island_removal_mode 0)
			)
			(polygon
				(pts
					(xy 141.683232 -109.412786) (xy 142.53718 -109.412786) (xy 142.53718 -110.076996) (xy 141.683232 -110.076996)
				)
			)
		)
		(zone
			(layer "F.Cu")
			(hatch none 0.5)
			(connect_pads
				(clearance 0)
			)
			(min_thickness 0.25)
			(keepout
				(tracks allowed)
				(vias not_allowed)
				(pads allowed)
				(copperpour not_allowed)
				(footprints allowed)
			)
			(placement
				(enabled no)
				(sheetname "")
			)
			(fill
				(thermal_gap 0.5)
				(thermal_bridge_width 0.5)
				(island_removal_mode 0)
			)
			(polygon
				(pts
					(xy 142.332202 -111.87303) (xy 143.637 -111.87303) (xy 143.637 -112.777778) (xy 142.332202 -112.777778)
				)
			)
		)
		(zone
			(layer "F.Cu")
			(hatch none 0.5)
			(connect_pads
				(clearance 0)
			)
			(min_thickness 0.25)
			(keepout
				(tracks not_allowed)
				(vias allowed)
				(pads allowed)
				(copperpour not_allowed)
				(footprints allowed)
			)
			(placement
				(enabled no)
				(sheetname "")
			)
			(fill
				(thermal_gap 0.5)
				(thermal_bridge_width 0.5)
				(island_removal_mode 0)
			)
			(polygon
				(pts
					(xy 142.332202 -111.87303) (xy 143.637 -111.87303) (xy 143.637 -112.777778) (xy 142.332202 -112.777778)
				)
			)
		)
		(zone
			(layer "F.Cu")
			(hatch none 0.5)
			(connect_pads
				(clearance 0)
			)
			(min_thickness 0.25)
			(keepout
				(tracks allowed)
				(vias not_allowed)
				(pads allowed)
				(copperpour not_allowed)
				(footprints allowed)
			)
			(placement
				(enabled no)
				(sheetname "")
			)
			(fill
				(thermal_gap 0.5)
				(thermal_bridge_width 0.5)
				(island_removal_mode 0)
			)
			(polygon
				(pts
					(xy 142.923006 -107.22229) (xy 143.637 -107.22229) (xy 143.637 -108.127038) (xy 142.923006 -108.127038)
				)
			)
		)
		(zone
			(layer "F.Cu")
			(hatch none 0.5)
			(connect_pads
				(clearance 0)
			)
			(min_thickness 0.25)
			(keepout
				(tracks not_allowed)
				(vias allowed)
				(pads allowed)
				(copperpour not_allowed)
				(footprints allowed)
			)
			(placement
				(enabled no)
				(sheetname "")
			)
			(fill
				(thermal_gap 0.5)
				(thermal_bridge_width 0.5)
				(island_removal_mode 0)
			)
			(polygon
				(pts
					(xy 142.923006 -107.22229) (xy 143.637 -107.22229) (xy 143.637 -108.127038) (xy 142.923006 -108.127038)
				)
			)
		)
		(zone
			(layer "F.Cu")
			(hatch none 0.5)
			(connect_pads
				(clearance 0)
			)
			(min_thickness 0.25)
			(keepout
				(tracks allowed)
				(vias not_allowed)
				(pads allowed)
				(copperpour not_allowed)
				(footprints allowed)
			)
			(placement
				(enabled no)
				(sheetname "")
			)
			(fill
				(thermal_gap 0.5)
				(thermal_bridge_width 0.5)
				(island_removal_mode 0)
			)
			(polygon
				(pts
					(xy 151.908002 -111.87303) (xy 152.54732 -111.87303) (xy 152.54732 -112.777778) (xy 151.908002 -112.777778)
				)
			)
		)
		(zone
			(layer "F.Cu")
			(hatch none 0.5)
			(connect_pads
				(clearance 0)
			)
			(min_thickness 0.25)
			(keepout
				(tracks not_allowed)
				(vias allowed)
				(pads allowed)
				(copperpour not_allowed)
				(footprints allowed)
			)
			(placement
				(enabled no)
				(sheetname "")
			)
			(fill
				(thermal_gap 0.5)
				(thermal_bridge_width 0.5)
				(island_removal_mode 0)
			)
			(polygon
				(pts
					(xy 151.908002 -111.87303) (xy 152.54732 -111.87303) (xy 152.54732 -112.777778) (xy 151.908002 -112.777778)
				)
			)
		)
		(zone
			(layer "F.Cu")
			(hatch none 0.5)
			(connect_pads
				(clearance 0)
			)
			(min_thickness 0.25)
			(keepout
				(tracks allowed)
				(vias not_allowed)
				(pads allowed)
				(copperpour not_allowed)
				(footprints allowed)
			)
			(placement
				(enabled no)
				(sheetname "")
			)
			(fill
				(thermal_gap 0.5)
				(thermal_bridge_width 0.5)
				(island_removal_mode 0)
			)
			(polygon
				(pts
					(xy 151.908002 -107.22229) (xy 153.162 -107.22229) (xy 153.162 -108.127038) (xy 151.908002 -108.127038)
				)
			)
		)
		(zone
			(layer "F.Cu")
			(hatch none 0.5)
			(connect_pads
				(clearance 0)
			)
			(min_thickness 0.25)
			(keepout
				(tracks not_allowed)
				(vias allowed)
				(pads allowed)
				(copperpour not_allowed)
				(footprints allowed)
			)
			(placement
				(enabled no)
				(sheetname "")
			)
			(fill
				(thermal_gap 0.5)
				(thermal_bridge_width 0.5)
				(island_removal_mode 0)
			)
			(polygon
				(pts
					(xy 151.908002 -107.22229) (xy 153.162 -107.22229) (xy 153.162 -108.127038) (xy 151.908002 -108.127038)
				)
			)
		)
	)
	(footprint ""
		(layer "F.Cu")
		(at 137.795 -66.286634)
		(property "Reference" "C359"
			(at 0 0 0)
			(layer "F.SilkS")
			(hide yes)
			(effects
				(font
					(size 1.27 1.27)
				)
			)
		)
		(property "Value" "SC220P50V3JN-GP"
			(at 0 -2.8194 0)
			(unlocked yes)
			(layer "F.Fab")
			(hide yes)
			(effects
				(font
					(size 1.016 1.016)
					(thickness 0.1524)
				)
			)
		)
		(property "Device Type" "C603H36"
			(at 0 -4.3434 0)
			(unlocked yes)
			(layer "F.Fab")
			(hide yes)
			(effects
				(font
					(size 1.016 1.016)
					(thickness 0.1524)
				)
			)
		)
		(duplicate_pad_numbers_are_jumpers no)
		(fp_line
			(start 0.508 0)
			(end -0.508 0)
			(stroke
				(width 0.2032)
				(type default)
			)
			(layer "F.SilkS")
		)
		(fp_rect
			(start -0.5842 1.3335)
			(end 0.5842 -1.3335)
			(stroke
				(width 0)
				(type default)
			)
			(fill no)
			(layer "F.CrtYd")
		)
		(fp_rect
			(start -0.5842 1.3335)
			(end 0.5842 -1.3335)
			(stroke
				(width 0)
				(type default)
			)
			(fill no)
			(layer "F.Fab")
		)
		(pad "1" smd custom
			(at 0 -0.762)
			(size 0.2159 0.2159)
			(layers "F.Cu" "F.Mask" "F.Paste")
			(net "I2C_C_BUF_SCL_CONN")
			(options
				(clearance outline)
				(anchor circle)
			)
			(primitives
				(gr_poly
					(pts
						(arc
							(start -0.3302 -0.4318)
							(mid -0.402042 -0.402042)
							(end -0.4318 -0.3302)
						)
						(arc
							(start -0.4318 0.3302)
							(mid -0.402042 0.402042)
							(end -0.3302 0.4318)
						)
						(arc
							(start 0.3302 0.4318)
							(mid 0.402042 0.402042)
							(end 0.4318 0.3302)
						)
						(arc
							(start 0.4318 -0.3302)
							(mid 0.402042 -0.402042)
							(end 0.3302 -0.4318)
						)
					)
					(width 0)
					(fill yes)
				)
			)
		)
		(pad "2" smd custom
			(at 0 0.762)
			(size 0.2159 0.2159)
			(layers "F.Cu" "F.Mask" "F.Paste")
			(net "GND")
			(options
				(clearance outline)
				(anchor circle)
			)
			(primitives
				(gr_poly
					(pts
						(arc
							(start -0.3302 -0.4318)
							(mid -0.402042 -0.402042)
							(end -0.4318 -0.3302)
						)
						(arc
							(start -0.4318 0.3302)
							(mid -0.402042 0.402042)
							(end -0.3302 0.4318)
						)
						(arc
							(start 0.3302 0.4318)
							(mid 0.402042 0.402042)
							(end 0.4318 0.3302)
						)
						(arc
							(start 0.4318 -0.3302)
							(mid 0.402042 -0.402042)
							(end 0.3302 -0.4318)
						)
					)
					(width 0)
					(fill yes)
				)
			)
		)
	)
	(footprint ""
		(layer "F.Cu")
		(at 13.650468 -94.361508)
		(property "Reference" "U51"
			(at 0 0 0)
			(layer "F.SilkS")
			(hide yes)
			(effects
				(font
					(size 1.27 1.27)
				)
			)
		)
		(property "Value" "PCA9511ADP-T-GP"
			(at 0 -13.1572 0)
			(unlocked yes)
			(layer "F.Fab")
			(hide yes)
			(effects
				(font
					(size 1.016 1.016)
					(thickness 0.1524)
				)
			)
		)
		(property "Device Type" "SSOIC8-2H44"
			(at 0 -15.1892 0)
			(unlocked yes)
			(layer "F.Fab")
			(hide yes)
			(effects
				(font
					(size 1.016 1.016)
					(thickness 0.1524)
				)
			)
		)
		(duplicate_pad_numbers_are_jumpers no)
		(fp_line
			(start -1.9304 -1.016)
			(end 1.0922 -1.016)
			(stroke
				(width 0.1524)
				(type default)
			)
			(layer "F.SilkS")
		)
		(fp_line
			(start -1.9304 1.016)
			(end -1.9304 -1.016)
			(stroke
				(width 0.1524)
				(type default)
			)
			(layer "F.SilkS")
		)
		(fp_line
			(start -1.7018 1.0414)
			(end -1.7018 2.9718)
			(stroke
				(width 0.635)
				(type default)
			)
			(layer "F.SilkS")
		)
		(fp_line
			(start -1.524 0)
			(end -1.9304 -0.4064)
			(stroke
				(width 0.1524)
				(type default)
			)
			(layer "F.SilkS")
		)
		(fp_line
			(start -1.524 0)
			(end -1.9304 0.4064)
			(stroke
				(width 0.1524)
				(type default)
			)
			(layer "F.SilkS")
		)
		(fp_line
			(start 1.0922 -1.016)
			(end 1.0922 1.016)
			(stroke
				(width 0.1524)
				(type default)
			)
			(layer "F.SilkS")
		)
		(fp_line
			(start 1.0922 1.016)
			(end -1.9304 1.016)
			(stroke
				(width 0.1524)
				(type default)
			)
			(layer "F.SilkS")
		)
		(fp_poly
			(pts
				(xy -1.1938 -1.016) (xy 1.0922 -1.016) (xy 1.0922 1.016) (xy -1.1938 1.016)
			)
			(stroke
				(width 0)
				(type default)
			)
			(fill yes)
			(layer "F.SilkS")
		)
		(fp_rect
			(start -2.0066 3.3401)
			(end 2.0066 -3.3401)
			(stroke
				(width 0)
				(type default)
			)
			(fill no)
			(layer "F.CrtYd")
		)
		(fp_poly
			(pts
				(xy -2.0066 -3.3401) (xy 2.0066 -3.3401) (xy 2.0066 3.3401) (xy -2.0066 3.3401)
			)
			(stroke
				(width 0)
				(type default)
			)
			(fill no)
			(layer "F.Fab")
		)
		(pad "1" smd rect
			(at -0.97536 2.0701)
			(size 0.4064 1.524)
			(layers "F.Cu" "F.Mask" "F.Paste")
			(net "I2C_C_BUF_EN")
		)
		(pad "2" smd rect
			(at -0.32512 2.0701)
			(size 0.4064 1.524)
			(layers "F.Cu" "F.Mask" "F.Paste")
			(net "I2C_C_BUF_SCLOUT")
		)
		(pad "3" smd rect
			(at 0.32512 2.0701)
			(size 0.4064 1.524)
			(layers "F.Cu" "F.Mask" "F.Paste")
			(net "I2C_C_BUF_SCLIN")
		)
		(pad "4" smd rect
			(at 0.97536 2.0701)
			(size 0.4064 1.524)
			(layers "F.Cu" "F.Mask" "F.Paste")
			(net "GND")
		)
		(pad "5" smd rect
			(at 0.97536 -2.0701)
			(size 0.4064 1.524)
			(layers "F.Cu" "F.Mask" "F.Paste")
			(net "I2C_C_BUF_READY")
		)
		(pad "6" smd rect
			(at 0.32512 -2.0701)
			(size 0.4064 1.524)
			(layers "F.Cu" "F.Mask" "F.Paste")
			(net "I2C_C_BUF_SDAIN")
		)
		(pad "7" smd rect
			(at -0.32512 -2.0701)
			(size 0.4064 1.524)
			(layers "F.Cu" "F.Mask" "F.Paste")
			(net "I2C_C_BUF_SDAOUT")
		)
		(pad "8" smd rect
			(at -0.97536 -2.0701)
			(size 0.4064 1.524)
			(layers "F.Cu" "F.Mask" "F.Paste")
			(net "P3V3")
		)
	)
)
